FILE_TYPE=LIBRARY_PARTS;
primitive '74CBTLV3126PW';
  pin
    '2A':
      PIN_NUMBER='(5)';
      BIDIRECTIONAL='TRUE';
      INPUT_LOAD='(-0.01,0.01)';
      OUTPUT_LOAD='(1.0,-1.0)';
    '3B':
      PIN_NUMBER='(8)';
      BIDIRECTIONAL='TRUE';
      INPUT_LOAD='(-0.01,0.01)';
      OUTPUT_LOAD='(1.0,-1.0)';
    '1OE':
      PIN_NUMBER='(1)';
      INPUT_LOAD='(-0.01,0.01)';
    '2OE':
      PIN_NUMBER='(4)';
      OUTPUT_LOAD='(1.0,-1.0)';
    '1B':
      PIN_NUMBER='(3)';
      BIDIRECTIONAL='TRUE';
      INPUT_LOAD='(-0.01,0.01)';
      OUTPUT_LOAD='(1.0,-1.0)';
    '2B':
      PIN_NUMBER='(6)';
      BIDIRECTIONAL='TRUE';
      INPUT_LOAD='(-0.01,0.01)';
      OUTPUT_LOAD='(1.0,-1.0)';
    '1A':
      PIN_NUMBER='(2)';
      PINUSE='POWER';
      NO_LOAD_CHECK='Both';
      NO_IO_CHECK='Both';
      NO_ASSERT_CHECK='TRUE';
      NO_DIR_CHECK='TRUE';
      ALLOW_CONNECT='TRUE';
    'GND':
      PIN_NUMBER='(7)';
      PINUSE='POWER';
      NO_LOAD_CHECK='Both';
      NO_IO_CHECK='Both';
      NO_ASSERT_CHECK='TRUE';
      NO_DIR_CHECK='TRUE';
      ALLOW_CONNECT='TRUE';
    '3A':
      PIN_NUMBER='(9)';
      BIDIRECTIONAL='TRUE';
      INPUT_LOAD='(-0.01,0.01)';
      OUTPUT_LOAD='(1.0,-1.0)';
    '3OE':
      PIN_NUMBER='(10)';
      BIDIRECTIONAL='TRUE';
      INPUT_LOAD='(-0.01,0.01)';
      OUTPUT_LOAD='(1.0,-1.0)';
    '4B':
      PIN_NUMBER='(11)';
      BIDIRECTIONAL='TRUE';
      INPUT_LOAD='(-0.01,0.01)';
      OUTPUT_LOAD='(1.0,-1.0)';
    '4A':
      PIN_NUMBER='(12)';
      BIDIRECTIONAL='TRUE';
      INPUT_LOAD='(-0.01,0.01)';
      OUTPUT_LOAD='(1.0,-1.0)';
    '4OE':
      PIN_NUMBER='(13)';
      BIDIRECTIONAL='TRUE';
      INPUT_LOAD='(-0.01,0.01)';
      OUTPUT_LOAD='(1.0,-1.0)';
    'VCC':
      PIN_NUMBER='(14)';
      BIDIRECTIONAL='TRUE';
      INPUT_LOAD='(-0.01,0.01)';
      OUTPUT_LOAD='(1.0,-1.0)';
  end_pin;
  body
    PART_NAME='74CBTLV3126PW';
    BODY_NAME='74CBTLV3126PW';
    JEDEC_TYPE='!TSOP14';
    PHYS_DES_PREFIX='U';
    CLASS='IC';
  end_body;
end_primitive;

END.
